(kicad_pcb
	(version 20260206)
	(generator "pcbnew")
	(generator_version "10.0")
	(general
		(thickness 1.6)
		(legacy_teardrops no)
	)
	(paper "A4")
	(title_block
		(title "01162023_DA0F0TEBIF0_F0T_Expander_BD_F_brd_V02_OCP.brd")
		(comment 1 "Grand Teton / footprints 5735-5740 of 9728")
	)
	(layers
		(0 "F.Cu" signal "TOP")
		(4 "In1.Cu" signal "GND")
		(6 "In2.Cu" signal "VCC")
		(8 "In3.Cu" signal "VCC1")
		(10 "In4.Cu" signal "GND1")
		(12 "In5.Cu" signal "IN1")
		(14 "In6.Cu" signal "GND2")
		(16 "In7.Cu" signal "IN2")
		(18 "In8.Cu" signal "GND3")
		(20 "In9.Cu" signal "IN3")
		(22 "In10.Cu" signal "GND4")
		(24 "In11.Cu" signal "IN4")
		(26 "In12.Cu" signal "GND5")
		(28 "In13.Cu" signal "IN5")
		(30 "In14.Cu" signal "GND6")
		(32 "In15.Cu" signal "IN6")
		(34 "In16.Cu" signal "GND7")
		(2 "B.Cu" signal "BOTTOM")
		(9 "F.Adhes" user "F.Adhesive")
		(11 "B.Adhes" user "B.Adhesive")
		(13 "F.Paste" user "Package Geometry/Pastemask Top")
		(15 "B.Paste" user "Package Geometry/Pastemask Bottom")
		(5 "F.SilkS" user "Ref Des/Silkscreen Top")
		(7 "B.SilkS" user "Ref Des/Silkscreen Bottom")
		(1 "F.Mask" user "Board Geometry/Soldermask Top")
		(3 "B.Mask" user "Board Geometry/Soldermask Bottom")
		(17 "Dwgs.User" user "User.Drawings")
		(19 "Cmts.User" user "User.Comments")
		(21 "Eco1.User" user "User.Eco1")
		(23 "Eco2.User" user "User.Eco2")
		(25 "Edge.Cuts" user "Board Geometry/Outline")
		(27 "Margin" user)
		(31 "F.CrtYd" user "Package Geometry/Place Bound Top")
		(29 "B.CrtYd" user "Package Geometry/Place Bound Bottom")
		(35 "F.Fab" user "Ref Des/Assembly Top")
		(33 "B.Fab" user "Ref Des/Assembly Bottom")
	)
	(footprint ""
		(layer "F.Cu")
		(at 243.564918 -314.424314)
		(property "Reference" "PC246"
			(at 0 0 0)
			(layer "F.SilkS")
			(hide yes)
			(effects
				(font
					(size 1.27 1.27)
				)
			)
		)
		(property "Value" ""
			(at 0 0 0)
			(layer "F.Fab")
			(effects
				(font
					(size 1.27 1.27)
				)
			)
		)
		(duplicate_pad_numbers_are_jumpers no)
		(fp_line
			(start -1.524 -0.762)
			(end 1.524 -0.762)
			(stroke
				(width 0.1524)
				(type default)
			)
			(layer "F.SilkS")
		)
		(fp_line
			(start -1.524 0.762)
			(end -1.524 -0.762)
			(stroke
				(width 0.1524)
				(type default)
			)
			(layer "F.SilkS")
		)
		(fp_line
			(start 1.524 -0.762)
			(end 1.524 0.762)
			(stroke
				(width 0.1524)
				(type default)
			)
			(layer "F.SilkS")
		)
		(fp_line
			(start 1.524 0.762)
			(end -1.524 0.762)
			(stroke
				(width 0.1524)
				(type default)
			)
			(layer "F.SilkS")
		)
		(fp_line
			(start -1.1049 -0.724916)
			(end -1.1049 0.724916)
			(stroke
				(width 0.1)
				(type default)
			)
			(layer "F.Fab")
		)
		(fp_line
			(start -1.1049 0.724916)
			(end 1.1049 0.724916)
			(stroke
				(width 0.1)
				(type default)
			)
			(layer "F.Fab")
		)
		(fp_line
			(start 1.1049 -0.724916)
			(end -1.1049 -0.724916)
			(stroke
				(width 0.1)
				(type default)
			)
			(layer "F.Fab")
		)
		(fp_line
			(start 1.1049 0.724916)
			(end 1.1049 -0.724916)
			(stroke
				(width 0.1)
				(type default)
			)
			(layer "F.Fab")
		)
		(pad "1" smd rect
			(at -0.889 0 180)
			(size 1.016 1.27)
			(layers "F.Cu" "F.Mask" "F.Paste")
			(net "SW_P12V_P1V25_PEX2_FLT")
		)
		(pad "2" smd rect
			(at 0.889 0 180)
			(size 1.016 1.27)
			(layers "F.Cu" "F.Mask" "F.Paste")
			(net "GND")
		)
	)
	(footprint ""
		(layer "F.Cu")
		(at 362.654596 -135.993632 -90)
		(property "Reference" "PC334"
			(at 0 0 270)
			(layer "F.SilkS")
			(hide yes)
			(effects
				(font
					(size 1.27 1.27)
				)
			)
		)
		(property "Value" ""
			(at 0 0 270)
			(layer "F.Fab")
			(effects
				(font
					(size 1.27 1.27)
				)
			)
		)
		(duplicate_pad_numbers_are_jumpers no)
		(fp_line
			(start -0.7874 0.4064)
			(end -0.7874 -0.4064)
			(stroke
				(width 0.1524)
				(type default)
			)
			(layer "F.SilkS")
		)
		(fp_line
			(start 0.7874 0.4064)
			(end -0.7874 0.4064)
			(stroke
				(width 0.1524)
				(type default)
			)
			(layer "F.SilkS")
		)
		(fp_line
			(start -0.7874 -0.4064)
			(end 0.7874 -0.4064)
			(stroke
				(width 0.1524)
				(type default)
			)
			(layer "F.SilkS")
		)
		(fp_line
			(start 0.7874 -0.4064)
			(end 0.7874 0.4064)
			(stroke
				(width 0.1524)
				(type default)
			)
			(layer "F.SilkS")
		)
		(fp_line
			(start -0.67945 0.3048)
			(end -0.67945 -0.305054)
			(stroke
				(width 0.1)
				(type default)
			)
			(layer "F.Fab")
		)
		(fp_line
			(start -0.12065 0.3048)
			(end -0.67945 0.3048)
			(stroke
				(width 0.1)
				(type default)
			)
			(layer "F.Fab")
		)
		(fp_line
			(start 0.120396 0.3048)
			(end 0.120396 0.2794)
			(stroke
				(width 0.1)
				(type default)
			)
			(layer "F.Fab")
		)
		(fp_line
			(start 0.67945 0.3048)
			(end 0.120396 0.3048)
			(stroke
				(width 0.1)
				(type default)
			)
			(layer "F.Fab")
		)
		(fp_line
			(start -0.12065 0.2794)
			(end -0.12065 0.3048)
			(stroke
				(width 0.1)
				(type default)
			)
			(layer "F.Fab")
		)
		(fp_line
			(start 0.120396 0.2794)
			(end -0.12065 0.2794)
			(stroke
				(width 0.1)
				(type default)
			)
			(layer "F.Fab")
		)
		(fp_line
			(start -0.12065 -0.2794)
			(end 0.12065 -0.2794)
			(stroke
				(width 0.1)
				(type default)
			)
			(layer "F.Fab")
		)
		(fp_line
			(start 0.12065 -0.2794)
			(end 0.12065 -0.3048)
			(stroke
				(width 0.1)
				(type default)
			)
			(layer "F.Fab")
		)
		(fp_line
			(start 0.12065 -0.3048)
			(end 0.67945 -0.3048)
			(stroke
				(width 0.1)
				(type default)
			)
			(layer "F.Fab")
		)
		(fp_line
			(start 0.67945 -0.3048)
			(end 0.67945 0.3048)
			(stroke
				(width 0.1)
				(type default)
			)
			(layer "F.Fab")
		)
		(fp_line
			(start -0.67945 -0.305054)
			(end -0.12065 -0.305054)
			(stroke
				(width 0.1)
				(type default)
			)
			(layer "F.Fab")
		)
		(fp_line
			(start -0.12065 -0.305054)
			(end -0.12065 -0.2794)
			(stroke
				(width 0.1)
				(type default)
			)
			(layer "F.Fab")
		)
		(pad "1" smd circle
			(at -0.40005 0 270)
			(size 0 0)
			(layers "F.Cu" "F.Mask" "F.Paste")
			(net "P12V_NIC6_R")
		)
		(pad "2" smd circle
			(at 0.40005 0 270)
			(size 0 0)
			(layers "F.Cu" "F.Mask" "F.Paste")
			(net "GND")
		)
	)
	(footprint ""
		(layer "F.Cu")
		(at 358.993186 -151.737822 180)
		(property "Reference" "PR7044"
			(at 0 0 180)
			(layer "F.SilkS")
			(hide yes)
			(effects
				(font
					(size 1.27 1.27)
				)
			)
		)
		(property "Value" ""
			(at 0 0 180)
			(layer "F.Fab")
			(effects
				(font
					(size 1.27 1.27)
				)
			)
		)
		(duplicate_pad_numbers_are_jumpers no)
		(fp_line
			(start 0.7874 0.4064)
			(end -0.7874 0.4064)
			(stroke
				(width 0.1524)
				(type default)
			)
			(layer "F.SilkS")
		)
		(fp_line
			(start 0.7874 -0.4064)
			(end 0.7874 0.4064)
			(stroke
				(width 0.1524)
				(type default)
			)
			(layer "F.SilkS")
		)
		(fp_line
			(start -0.7874 0.4064)
			(end -0.7874 -0.4064)
			(stroke
				(width 0.1524)
				(type default)
			)
			(layer "F.SilkS")
		)
		(fp_line
			(start -0.7874 -0.4064)
			(end 0.7874 -0.4064)
			(stroke
				(width 0.1524)
				(type default)
			)
			(layer "F.SilkS")
		)
		(fp_line
			(start 0.67945 0.3048)
			(end 0.120396 0.3048)
			(stroke
				(width 0.1)
				(type default)
			)
			(layer "F.Fab")
		)
		(fp_line
			(start 0.67945 -0.3048)
			(end 0.67945 0.3048)
			(stroke
				(width 0.1)
				(type default)
			)
			(layer "F.Fab")
		)
		(fp_line
			(start 0.12065 -0.2794)
			(end 0.12065 -0.3048)
			(stroke
				(width 0.1)
				(type default)
			)
			(layer "F.Fab")
		)
		(fp_line
			(start 0.12065 -0.3048)
			(end 0.67945 -0.3048)
			(stroke
				(width 0.1)
				(type default)
			)
			(layer "F.Fab")
		)
		(fp_line
			(start 0.120396 0.3048)
			(end 0.120396 0.2794)
			(stroke
				(width 0.1)
				(type default)
			)
			(layer "F.Fab")
		)
		(fp_line
			(start 0.120396 0.2794)
			(end -0.12065 0.2794)
			(stroke
				(width 0.1)
				(type default)
			)
			(layer "F.Fab")
		)
		(fp_line
			(start -0.12065 0.3048)
			(end -0.67945 0.3048)
			(stroke
				(width 0.1)
				(type default)
			)
			(layer "F.Fab")
		)
		(fp_line
			(start -0.12065 0.2794)
			(end -0.12065 0.3048)
			(stroke
				(width 0.1)
				(type default)
			)
			(layer "F.Fab")
		)
		(fp_line
			(start -0.12065 -0.2794)
			(end 0.12065 -0.2794)
			(stroke
				(width 0.1)
				(type default)
			)
			(layer "F.Fab")
		)
		(fp_line
			(start -0.12065 -0.305054)
			(end -0.12065 -0.2794)
			(stroke
				(width 0.1)
				(type default)
			)
			(layer "F.Fab")
		)
		(fp_line
			(start -0.67945 0.3048)
			(end -0.67945 -0.305054)
			(stroke
				(width 0.1)
				(type default)
			)
			(layer "F.Fab")
		)
		(fp_line
			(start -0.67945 -0.305054)
			(end -0.12065 -0.305054)
			(stroke
				(width 0.1)
				(type default)
			)
			(layer "F.Fab")
		)
		(pad "1" smd circle
			(at -0.40005 0 180)
			(size 0 0)
			(layers "F.Cu" "F.Mask" "F.Paste")
			(net "P12V_NIC6_R")
		)
		(pad "2" smd circle
			(at 0.40005 0 180)
			(size 0 0)
			(layers "F.Cu" "F.Mask" "F.Paste")
			(net "P12V_NIC6_CO_AVIN_PD")
		)
	)
	(footprint ""
		(layer "F.Cu")
		(at 319.140332 -141.404848 -90)
		(property "Reference" "R298"
			(at 0 0 270)
			(layer "F.SilkS")
			(hide yes)
			(effects
				(font
					(size 1.27 1.27)
				)
			)
		)
		(property "Value" ""
			(at 0 0 270)
			(layer "F.Fab")
			(effects
				(font
					(size 1.27 1.27)
				)
			)
		)
		(duplicate_pad_numbers_are_jumpers no)
		(fp_line
			(start -0.7874 0.4064)
			(end -0.7874 -0.4064)
			(stroke
				(width 0.1524)
				(type default)
			)
			(layer "F.SilkS")
		)
		(fp_line
			(start 0.7874 0.4064)
			(end -0.7874 0.4064)
			(stroke
				(width 0.1524)
				(type default)
			)
			(layer "F.SilkS")
		)
		(fp_line
			(start -0.7874 -0.4064)
			(end 0.7874 -0.4064)
			(stroke
				(width 0.1524)
				(type default)
			)
			(layer "F.SilkS")
		)
		(fp_line
			(start 0.7874 -0.4064)
			(end 0.7874 0.4064)
			(stroke
				(width 0.1524)
				(type default)
			)
			(layer "F.SilkS")
		)
		(fp_line
			(start -0.67945 0.3048)
			(end -0.67945 -0.305054)
			(stroke
				(width 0.1)
				(type default)
			)
			(layer "F.Fab")
		)
		(fp_line
			(start -0.12065 0.3048)
			(end -0.67945 0.3048)
			(stroke
				(width 0.1)
				(type default)
			)
			(layer "F.Fab")
		)
		(fp_line
			(start 0.120396 0.3048)
			(end 0.120396 0.2794)
			(stroke
				(width 0.1)
				(type default)
			)
			(layer "F.Fab")
		)
		(fp_line
			(start 0.67945 0.3048)
			(end 0.120396 0.3048)
			(stroke
				(width 0.1)
				(type default)
			)
			(layer "F.Fab")
		)
		(fp_line
			(start -0.12065 0.2794)
			(end -0.12065 0.3048)
			(stroke
				(width 0.1)
				(type default)
			)
			(layer "F.Fab")
		)
		(fp_line
			(start 0.120396 0.2794)
			(end -0.12065 0.2794)
			(stroke
				(width 0.1)
				(type default)
			)
			(layer "F.Fab")
		)
		(fp_line
			(start -0.12065 -0.2794)
			(end 0.12065 -0.2794)
			(stroke
				(width 0.1)
				(type default)
			)
			(layer "F.Fab")
		)
		(fp_line
			(start 0.12065 -0.2794)
			(end 0.12065 -0.3048)
			(stroke
				(width 0.1)
				(type default)
			)
			(layer "F.Fab")
		)
		(fp_line
			(start 0.12065 -0.3048)
			(end 0.67945 -0.3048)
			(stroke
				(width 0.1)
				(type default)
			)
			(layer "F.Fab")
		)
		(fp_line
			(start 0.67945 -0.3048)
			(end 0.67945 0.3048)
			(stroke
				(width 0.1)
				(type default)
			)
			(layer "F.Fab")
		)
		(fp_line
			(start -0.67945 -0.305054)
			(end -0.12065 -0.305054)
			(stroke
				(width 0.1)
				(type default)
			)
			(layer "F.Fab")
		)
		(fp_line
			(start -0.12065 -0.305054)
			(end -0.12065 -0.2794)
			(stroke
				(width 0.1)
				(type default)
			)
			(layer "F.Fab")
		)
		(pad "1" smd circle
			(at -0.40005 0 270)
			(size 0 0)
			(layers "F.Cu" "F.Mask" "F.Paste")
			(net "PRSNT_NIC5_R_N")
		)
		(pad "2" smd circle
			(at 0.40005 0 270)
			(size 0 0)
			(layers "F.Cu" "F.Mask" "F.Paste")
			(net "PRSNT_NIC5_N")
		)
	)
	(footprint ""
		(layer "F.Cu")
		(at 306.227734 -35.876738)
		(property "Reference" "R6095"
			(at 0 0 0)
			(layer "F.SilkS")
			(hide yes)
			(effects
				(font
					(size 1.27 1.27)
				)
			)
		)
		(property "Value" ""
			(at 0 0 0)
			(layer "F.Fab")
			(effects
				(font
					(size 1.27 1.27)
				)
			)
		)
		(duplicate_pad_numbers_are_jumpers no)
		(fp_line
			(start -0.7874 -0.4064)
			(end 0.7874 -0.4064)
			(stroke
				(width 0.1524)
				(type default)
			)
			(layer "F.SilkS")
		)
		(fp_line
			(start -0.7874 0.4064)
			(end -0.7874 -0.4064)
			(stroke
				(width 0.1524)
				(type default)
			)
			(layer "F.SilkS")
		)
		(fp_line
			(start 0.7874 -0.4064)
			(end 0.7874 0.4064)
			(stroke
				(width 0.1524)
				(type default)
			)
			(layer "F.SilkS")
		)
		(fp_line
			(start 0.7874 0.4064)
			(end -0.7874 0.4064)
			(stroke
				(width 0.1524)
				(type default)
			)
			(layer "F.SilkS")
		)
		(fp_line
			(start -0.67945 -0.305054)
			(end -0.12065 -0.305054)
			(stroke
				(width 0.1)
				(type default)
			)
			(layer "F.Fab")
		)
		(fp_line
			(start -0.67945 0.3048)
			(end -0.67945 -0.305054)
			(stroke
				(width 0.1)
				(type default)
			)
			(layer "F.Fab")
		)
		(fp_line
			(start -0.12065 -0.305054)
			(end -0.12065 -0.2794)
			(stroke
				(width 0.1)
				(type default)
			)
			(layer "F.Fab")
		)
		(fp_line
			(start -0.12065 -0.2794)
			(end 0.12065 -0.2794)
			(stroke
				(width 0.1)
				(type default)
			)
			(layer "F.Fab")
		)
		(fp_line
			(start -0.12065 0.2794)
			(end -0.12065 0.3048)
			(stroke
				(width 0.1)
				(type default)
			)
			(layer "F.Fab")
		)
		(fp_line
			(start -0.12065 0.3048)
			(end -0.67945 0.3048)
			(stroke
				(width 0.1)
				(type default)
			)
			(layer "F.Fab")
		)
		(fp_line
			(start 0.120396 0.2794)
			(end -0.12065 0.2794)
			(stroke
				(width 0.1)
				(type default)
			)
			(layer "F.Fab")
		)
		(fp_line
			(start 0.120396 0.3048)
			(end 0.120396 0.2794)
			(stroke
				(width 0.1)
				(type default)
			)
			(layer "F.Fab")
		)
		(fp_line
			(start 0.12065 -0.3048)
			(end 0.67945 -0.3048)
			(stroke
				(width 0.1)
				(type default)
			)
			(layer "F.Fab")
		)
		(fp_line
			(start 0.12065 -0.2794)
			(end 0.12065 -0.3048)
			(stroke
				(width 0.1)
				(type default)
			)
			(layer "F.Fab")
		)
		(fp_line
			(start 0.67945 -0.3048)
			(end 0.67945 0.3048)
			(stroke
				(width 0.1)
				(type default)
			)
			(layer "F.Fab")
		)
		(fp_line
			(start 0.67945 0.3048)
			(end 0.120396 0.3048)
			(stroke
				(width 0.1)
				(type default)
			)
			(layer "F.Fab")
		)
		(pad "1" smd circle
			(at -0.40005 0)
			(size 0 0)
			(layers "F.Cu" "F.Mask" "F.Paste")
			(net "PWRGD_P3V3_SSD11_D")
		)
		(pad "2" smd circle
			(at 0.40005 0)
			(size 0 0)
			(layers "F.Cu" "F.Mask" "F.Paste")
			(net "PWRGD_P3V3_SSD11_R")
		)
	)
	(footprint ""
		(layer "F.Cu")
		(at 19.408394 -142.455392 180)
		(property "Reference" "R682"
			(at 0 0 180)
			(layer "F.SilkS")
			(hide yes)
			(effects
				(font
					(size 1.27 1.27)
				)
			)
		)
		(property "Value" ""
			(at 0 0 180)
			(layer "F.Fab")
			(effects
				(font
					(size 1.27 1.27)
				)
			)
		)
		(duplicate_pad_numbers_are_jumpers no)
		(fp_line
			(start 3.937508 1.8796)
			(end 3.937508 -1.8796)
			(stroke
				(width 0.1524)
				(type default)
			)
			(layer "F.SilkS")
		)
		(fp_line
			(start 3.937508 -1.8796)
			(end -3.937508 -1.8796)
			(stroke
				(width 0.1524)
				(type default)
			)
			(layer "F.SilkS")
		)
		(fp_line
			(start -3.937508 1.8796)
			(end 3.937508 1.8796)
			(stroke
				(width 0.1524)
				(type default)
			)
			(layer "F.SilkS")
		)
		(fp_line
			(start -3.937508 -1.8796)
			(end -3.937508 1.8796)
			(stroke
				(width 0.1524)
				(type default)
			)
			(layer "F.SilkS")
		)
		(fp_line
			(start 3.275076 1.674876)
			(end 3.275076 -1.674876)
			(stroke
				(width 0.1)
				(type default)
			)
			(layer "F.Fab")
		)
		(fp_line
			(start 3.275076 -1.674876)
			(end -3.275076 -1.674876)
			(stroke
				(width 0.1)
				(type default)
			)
			(layer "F.Fab")
		)
		(fp_line
			(start -3.275076 1.674876)
			(end 3.275076 1.674876)
			(stroke
				(width 0.1)
				(type default)
			)
			(layer "F.Fab")
		)
		(fp_line
			(start -3.275076 -1.674876)
			(end -3.275076 1.674876)
			(stroke
				(width 0.1)
				(type default)
			)
			(layer "F.Fab")
		)
		(pad "1" smd rect
			(at -2.350008 0 180)
			(size 2.921 3.5052)
			(layers "F.Cu" "F.Mask" "F.Paste")
			(net "P12V_NIC0")
		)
		(pad "2" smd rect
			(at 2.350008 0 180)
			(size 2.921 3.5052)
			(layers "F.Cu" "F.Mask" "F.Paste")
			(net "P12V_NIC0_R")
		)
	)
)
